# S9S_MB_2U (Grand Teton) — schematic netlist excerpt (pin names and nets, part order shuffled) for the footprints in the layout excerpt that follows; sources: Cadence DE-HDL packaged netlist, KiCad conversion of 03242023_DA0F0TMBIJ0_F0T_Motherboard_J_brd_V01_OCP.brd

R3042  Q_RES  10K 1% EMPTY  pkg 0402LF  page 204 : A = P1V05_PCH_AUX ; B = H_CPU_ERR1_PCH_R_N
C1203  Q_CAP  10UF 6.3V 20% X6S  pkg C0402  page 189 : A = P1V05_PCH_AUX ; B = GND

(kicad_pcb
	(version 20260206)
	(generator "pcbnew")
	(generator_version "10.0")
	(general
		(thickness 1.6)
		(legacy_teardrops no)
	)
	(paper "A4")
	(title_block
		(title "03242023_DA0F0TMBIJ0_F0T_Motherboard_J_brd_V01_OCP.brd")
		(comment 1 "Grand Teton / footprints 4190-4191 of 6105")
	)
	(layers
		(0 "F.Cu" signal "TOP")
		(4 "In1.Cu" signal "GND")
		(6 "In2.Cu" signal "IN1")
		(8 "In3.Cu" signal "GND1")
		(10 "In4.Cu" signal "IN2")
		(12 "In5.Cu" signal "GND2")
		(14 "In6.Cu" signal "IN3")
		(16 "In7.Cu" signal "GND3")
		(18 "In8.Cu" signal "VCC")
		(20 "In9.Cu" signal "VCC1")
		(22 "In10.Cu" signal "GND4")
		(24 "In11.Cu" signal "IN4")
		(26 "In12.Cu" signal "GND5")
		(28 "In13.Cu" signal "IN5")
		(30 "In14.Cu" signal "GND6")
		(32 "In15.Cu" signal "IN6")
		(34 "In16.Cu" signal "GND7")
		(2 "B.Cu" signal "BOTTOM")
		(9 "F.Adhes" user "F.Adhesive")
		(11 "B.Adhes" user "B.Adhesive")
		(13 "F.Paste" user "Package Geometry/Pastemask Top")
		(15 "B.Paste" user "Package Geometry/Pastemask Bottom")
		(5 "F.SilkS" user "Ref Des/Silkscreen Top")
		(7 "B.SilkS" user "Ref Des/Silkscreen Bottom")
		(1 "F.Mask" user "Board Geometry/Soldermask Top")
		(3 "B.Mask" user "Board Geometry/Soldermask Bottom")
		(17 "Dwgs.User" user "User.Drawings")
		(19 "Cmts.User" user "User.Comments")
		(21 "Eco1.User" user "User.Eco1")
		(23 "Eco2.User" user "User.Eco2")
		(25 "Edge.Cuts" user "Board Geometry/Outline")
		(27 "Margin" user)
		(31 "F.CrtYd" user "Package Geometry/Place Bound Top")
		(29 "B.CrtYd" user "Package Geometry/Place Bound Bottom")
		(35 "F.Fab" user "Ref Des/Assembly Top")
		(33 "B.Fab" user "Ref Des/Assembly Bottom")
	)
	(footprint ""
		(layer "B.Cu")
		(at 320.178176 -58.298588 -90)
		(property "Reference" "R3042"
			(at 0 0 90)
			(layer "B.SilkS")
			(hide yes)
			(effects
				(font
					(size 1.27 1.27)
				)
				(justify mirror)
			)
		)
		(property "Value" ""
			(at 0 0 90)
			(layer "B.Fab")
			(effects
				(font
					(size 1.27 1.27)
				)
				(justify mirror)
			)
		)
		(duplicate_pad_numbers_are_jumpers no)
		(fp_line
			(start -0.7874 0.4064)
			(end 0.7874 0.4064)
			(stroke
				(width 0.1524)
				(type default)
			)
			(layer "B.SilkS")
		)
		(fp_line
			(start 0.7874 0.4064)
			(end 0.7874 -0.4064)
			(stroke
				(width 0.1524)
				(type default)
			)
			(layer "B.SilkS")
		)
		(fp_line
			(start -0.7874 -0.4064)
			(end -0.7874 0.4064)
			(stroke
				(width 0.1524)
				(type default)
			)
			(layer "B.SilkS")
		)
		(fp_line
			(start 0.7874 -0.4064)
			(end -0.7874 -0.4064)
			(stroke
				(width 0.1524)
				(type default)
			)
			(layer "B.SilkS")
		)
		(fp_line
			(start -0.67945 0.3048)
			(end -0.120396 0.3048)
			(stroke
				(width 0.1)
				(type default)
			)
			(layer "B.Fab")
		)
		(fp_line
			(start -0.120396 0.3048)
			(end -0.120396 0.2794)
			(stroke
				(width 0.1)
				(type default)
			)
			(layer "B.Fab")
		)
		(fp_line
			(start 0.12065 0.3048)
			(end 0.67945 0.3048)
			(stroke
				(width 0.1)
				(type default)
			)
			(layer "B.Fab")
		)
		(fp_line
			(start 0.67945 0.3048)
			(end 0.67945 -0.305054)
			(stroke
				(width 0.1)
				(type default)
			)
			(layer "B.Fab")
		)
		(fp_line
			(start -0.120396 0.2794)
			(end 0.12065 0.2794)
			(stroke
				(width 0.1)
				(type default)
			)
			(layer "B.Fab")
		)
		(fp_line
			(start 0.12065 0.2794)
			(end 0.12065 0.3048)
			(stroke
				(width 0.1)
				(type default)
			)
			(layer "B.Fab")
		)
		(fp_line
			(start -0.12065 -0.2794)
			(end -0.12065 -0.3048)
			(stroke
				(width 0.1)
				(type default)
			)
			(layer "B.Fab")
		)
		(fp_line
			(start 0.12065 -0.2794)
			(end -0.12065 -0.2794)
			(stroke
				(width 0.1)
				(type default)
			)
			(layer "B.Fab")
		)
		(fp_line
			(start -0.67945 -0.3048)
			(end -0.67945 0.3048)
			(stroke
				(width 0.1)
				(type default)
			)
			(layer "B.Fab")
		)
		(fp_line
			(start -0.12065 -0.3048)
			(end -0.67945 -0.3048)
			(stroke
				(width 0.1)
				(type default)
			)
			(layer "B.Fab")
		)
		(fp_line
			(start 0.12065 -0.305054)
			(end 0.12065 -0.2794)
			(stroke
				(width 0.1)
				(type default)
			)
			(layer "B.Fab")
		)
		(fp_line
			(start 0.67945 -0.305054)
			(end 0.12065 -0.305054)
			(stroke
				(width 0.1)
				(type default)
			)
			(layer "B.Fab")
		)
		(pad "1" smd circle
			(at 0.40005 0 90)
			(size 0 0)
			(layers "B.Cu" "B.Mask" "B.Paste")
			(net "P1V05_PCH_AUX")
		)
		(pad "2" smd circle
			(at -0.40005 0 90)
			(size 0 0)
			(layers "B.Cu" "B.Mask" "B.Paste")
			(net "H_CPU_ERR1_PCH_R_N")
		)
	)
	(footprint ""
		(layer "B.Cu")
		(at 336.17408 -43.504358)
		(property "Reference" "C1203"
			(at 0 0 0)
			(layer "B.SilkS")
			(hide yes)
			(effects
				(font
					(size 1.27 1.27)
				)
				(justify mirror)
			)
		)
		(property "Value" ""
			(at 0 0 0)
			(layer "B.Fab")
			(effects
				(font
					(size 1.27 1.27)
				)
				(justify mirror)
			)
		)
		(duplicate_pad_numbers_are_jumpers no)
		(fp_line
			(start -0.7874 -0.4064)
			(end -0.7874 0.4064)
			(stroke
				(width 0.1524)
				(type default)
			)
			(layer "B.SilkS")
		)
		(fp_line
			(start -0.7874 0.4064)
			(end 0.7874 0.4064)
			(stroke
				(width 0.1524)
				(type default)
			)
			(layer "B.SilkS")
		)
		(fp_line
			(start 0.7874 -0.4064)
			(end -0.7874 -0.4064)
			(stroke
				(width 0.1524)
				(type default)
			)
			(layer "B.SilkS")
		)
		(fp_line
			(start 0.7874 0.4064)
			(end 0.7874 -0.4064)
			(stroke
				(width 0.1524)
				(type default)
			)
			(layer "B.SilkS")
		)
		(fp_line
			(start -0.67945 -0.3048)
			(end -0.67945 0.3048)
			(stroke
				(width 0.1)
				(type default)
			)
			(layer "B.Fab")
		)
		(fp_line
			(start -0.67945 0.3048)
			(end -0.120396 0.3048)
			(stroke
				(width 0.1)
				(type default)
			)
			(layer "B.Fab")
		)
		(fp_line
			(start -0.12065 -0.3048)
			(end -0.67945 -0.3048)
			(stroke
				(width 0.1)
				(type default)
			)
			(layer "B.Fab")
		)
		(fp_line
			(start -0.12065 -0.2794)
			(end -0.12065 -0.3048)
			(stroke
				(width 0.1)
				(type default)
			)
			(layer "B.Fab")
		)
		(fp_line
			(start -0.120396 0.2794)
			(end 0.12065 0.2794)
			(stroke
				(width 0.1)
				(type default)
			)
			(layer "B.Fab")
		)
		(fp_line
			(start -0.120396 0.3048)
			(end -0.120396 0.2794)
			(stroke
				(width 0.1)
				(type default)
			)
			(layer "B.Fab")
		)
		(fp_line
			(start 0.12065 -0.305054)
			(end 0.12065 -0.2794)
			(stroke
				(width 0.1)
				(type default)
			)
			(layer "B.Fab")
		)
		(fp_line
			(start 0.12065 -0.2794)
			(end -0.12065 -0.2794)
			(stroke
				(width 0.1)
				(type default)
			)
			(layer "B.Fab")
		)
		(fp_line
			(start 0.12065 0.2794)
			(end 0.12065 0.3048)
			(stroke
				(width 0.1)
				(type default)
			)
			(layer "B.Fab")
		)
		(fp_line
			(start 0.12065 0.3048)
			(end 0.67945 0.3048)
			(stroke
				(width 0.1)
				(type default)
			)
			(layer "B.Fab")
		)
		(fp_line
			(start 0.67945 -0.305054)
			(end 0.12065 -0.305054)
			(stroke
				(width 0.1)
				(type default)
			)
			(layer "B.Fab")
		)
		(fp_line
			(start 0.67945 0.3048)
			(end 0.67945 -0.305054)
			(stroke
				(width 0.1)
				(type default)
			)
			(layer "B.Fab")
		)
		(pad "1" smd circle
			(at 0.40005 0 180)
			(size 0 0)
			(layers "B.Cu" "B.Mask" "B.Paste")
			(net "P1V05_PCH_AUX")
		)
		(pad "2" smd circle
			(at -0.40005 0 180)
			(size 0 0)
			(layers "B.Cu" "B.Mask" "B.Paste")
			(net "GND")
		)
	)
)
